FILE_TYPE = CONNECTIVITY;
{Allegro Design Entry HDL 16.6-p007 (v16-6-112F) 10/10/2012}
"PAGE_NUMBER" = 130;
0"NC";
1"GND\g";
2"GND\g";
3"GND\g";
4"GND\g";
5"GND\g";
6"P1V8_PCH_STBY\g";
7"GND\g";
8"GND\g";
9"GND\g";
10"P1V8_PCH_STBY\g";
11"GND\g";
12"GND\g";
13"P1V8_PCH_STBY\g";
14"P3V3_STBY\g";
15"P3V3_STBY\g";
16"P3V3_STBY\g";
17"P3V3_STBY\g";
18"GND\g";
19"P3V3_STBY\g";
20"P3V3_STBY\g";
21"P3V3_STBY\g";
22"A_PVCCRTC_EXT_CAP";
%"CAP_A"
"1","(1925,1600)","0","dev_discrete","I12";
;
LOCATION"C2N20"
PART_NUMBER"D97712-004"
VALUE"1.0UF"
TOLERANCE"10%"
PACK_TYPE"0402V"
VOLTAGE"6.3V"
MATERIAL"X6S"
CDS_LOCATION"C2N20"
BOM_COST"SB"
CDS_LIB"dev_discrete"
CDS_SEC"1"
$SEC"1"
ROOM"SB_DECOUPLING";
"B"
$PN"2"1;
"A"
$PN"1"21;
%"GND"
"1","(1925,1300)","0","mstr_symbols","I13";
;
VOLTAGE"0"
BOM_COST"SB"
SIZE"1B"
CDS_LIB"mstr_symbols"
BODY_TYPE"PLUMBING"
ROOM"SB_DECOUPLING"
HDL_POWER"GND";
"A\NAC"1;
%"GND"
"1","(650,2350)","0","mstr_symbols","I14";
;
VOLTAGE"0"
BOM_COST"SB"
CDS_LIB"mstr_symbols"
SIZE"1B"
BODY_TYPE"PLUMBING"
ROOM"SB_DECOUPLING"
HDL_POWER"GND";
"A\NAC"2;
%"CAP"
"1","(425,2650)","0","mstr_discrete","I15";
;
LOCATION"C2N21"
PART_NUMBER"E15431-002"
VALUE"10UF"
TOLERANCE"20%"
PACK_TYPE"0603"
VOLTAGE"6.3V"
MATERIAL"X6S"
CDS_LIB"mstr_discrete"
BOM_COST"SB"
CDS_SEC"1"
$SEC"1"
CDS_LOCATION"C2N21"
ROOM"SB_DECOUPLING";
"A"
$PN"1"20;
"B"
$PN"2"2;
%"CAP_A"
"1","(0,2025)","2","dev_discrete","I16";
;
LOCATION"C3N29"
PART_NUMBER"A36096-030"
VALUE"0.1UF"
TOLERANCE"10%"
PACK_TYPE"0402V"
VOLTAGE"16V"
MATERIAL"X7R"
ROOM"SB_DECOUPLING"
CDS_LOCATION"C3N29"
BOM_COST"SB"
CDS_LIB"dev_discrete"
CDS_SEC"1"
$SEC"1";
"B"
$PN"2"3;
"A"
$PN"1"22;
%"GND"
"1","(0,1725)","0","mstr_symbols","I17";
;
VOLTAGE"0"
CDS_LIB"mstr_symbols"
SIZE"1B"
BOM_COST"SB"
BODY_TYPE"PLUMBING"
ROOM"SB_DECOUPLING"
HDL_POWER"GND";
"A\NAC"3;
%"CAP"
"1","(-2550,4925)","0","mstr_discrete","I19";
;
LOCATION"C8C3"
PART_NUMBER"E15431-002"
VALUE"10UF"
TOLERANCE"20%"
PACK_TYPE"0603"
VOLTAGE"6.3V"
MATERIAL"X6S"
CDS_LIB"mstr_discrete"
BOM_COST"SB"
CDS_SEC"1"
$SEC"1"
CDS_LOCATION"C8C3"
ROOM"SB_DECOUPLING";
"A"
$PN"1"14;
"B"
$PN"2"8;
%"CAP"
"1","(1125,5003)","0","mstr_discrete","I2";
;
CDS_SEC"1"
LOCATION"C7D2"
PART_NUMBER"E15431-002"
VALUE"10UF"
TOLERANCE"20%"
PACK_TYPE"0603"
VOLTAGE"6.3V"
MATERIAL"X6S"
SEC_TYPE"0603"
BOM_COST"SB"
CDS_LIB"mstr_discrete"
SEC"1"
CDS_LOCATION"C7D2"
ROOM"SB_DECOUPLING";
"A"
$PN"1"17;
"B"
$PN"2"5;
%"CAP"
"1","(-2975,4925)","0","mstr_discrete","I20";
;
LOCATION"C8C4"
VALUE"10UF"
TOLERANCE"20%"
PACK_TYPE"0603"
VOLTAGE"6.3V"
MATERIAL"X6S"
PART_NUMBER"E15431-002"
CDS_LIB"mstr_discrete"
BOM_COST"SB"
CDS_SEC"1"
$SEC"1"
CDS_LOCATION"C8C4"
ROOM"SB_DECOUPLING";
"A"
$PN"1"14;
"B"
$PN"2"8;
%"CAP"
"1","(-3375,4925)","0","mstr_discrete","I21";
;
LOCATION"C8C5"
PART_NUMBER"E15431-002"
VALUE"10UF"
TOLERANCE"20%"
PACK_TYPE"0603"
VOLTAGE"6.3V"
MATERIAL"X6S"
CDS_LIB"mstr_discrete"
BOM_COST"SB"
CDS_SEC"1"
$SEC"1"
CDS_LOCATION"C8C5"
ROOM"SB_DECOUPLING";
"A"
$PN"1"14;
"B"
$PN"2"8;
%"CAP"
"1","(-3775,4925)","0","mstr_discrete","I22";
;
LOCATION"C8C6"
PART_NUMBER"E15431-002"
VALUE"10UF"
TOLERANCE"20%"
PACK_TYPE"0603"
MATERIAL"X6S"
VOLTAGE"6.3V"
CDS_LIB"mstr_discrete"
BOM_COST"SB"
CDS_SEC"1"
$SEC"1"
CDS_LOCATION"C8C6"
ROOM"SB_DECOUPLING";
"A"
$PN"1"14;
"B"
$PN"2"8;
%"CAP"
"1","(-4175,4925)","0","mstr_discrete","I24";
;
LOCATION"C2N23"
PART_NUMBER"E15431-002"
VALUE"10UF"
TOLERANCE"20%"
PACK_TYPE"0603"
VOLTAGE"6.3V"
MATERIAL"X6S"
CDS_LIB"mstr_discrete"
BOM_COST"SB"
CDS_SEC"1"
$SEC"1"
CDS_LOCATION"C2N23"
ROOM"SB_DECOUPLING";
"A"
$PN"1"14;
"B"
$PN"2"8;
%"CAP"
"1","(-4575,4925)","0","mstr_discrete","I25";
;
LOCATION"C2N14"
PART_NUMBER"E15431-002"
TOLERANCE"20%"
PACK_TYPE"0603"
MATERIAL"X6S"
VALUE"10UF"
VOLTAGE"6.3V"
CDS_LIB"mstr_discrete"
BOM_COST"SB"
CDS_SEC"1"
$SEC"1"
CDS_LOCATION"C2N14"
ROOM"SB_DECOUPLING";
"A"
$PN"1"14;
"B"
$PN"2"8;
%"GND"
"1","(-1475,3625)","0","mstr_symbols","I27";
;
VOLTAGE"0.0V"
CDS_LIB"mstr_symbols"
SIZE"1B"
BOM_COST"SB"
BODY_TYPE"PLUMBING"
ROOM"SB_DECOUPLING"
HDL_POWER"GND";
"A\NAC"4;
%"CAP"
"1","(-1475,3925)","0","mstr_discrete","I28";
;
LOCATION"C2N17"
PART_NUMBER"E15431-002"
VALUE"10UF"
TOLERANCE"20%"
PACK_TYPE"0603"
VOLTAGE"6.3V"
MATERIAL"X6S"
CDS_LIB"mstr_discrete"
BOM_COST"SB"
CDS_SEC"1"
$SEC"1"
CDS_LOCATION"C2N17"
ROOM"SB_DECOUPLING";
"A"
$PN"1"16;
"B"
$PN"2"4;
%"CAP_A"
"1","(-3450,3925)","0","dev_discrete","I29";
;
LOCATION"C2N18"
PART_NUMBER"D97712-004"
VALUE"1.0UF"
TOLERANCE"10%"
PACK_TYPE"0402V"
VOLTAGE"6.3V"
MATERIAL"X6S"
CDS_LOCATION"C2N18"
BOM_COST"SB"
CDS_LIB"dev_discrete"
CDS_SEC"1"
$SEC"1"
ROOM"SB_DECOUPLING";
"B"
$PN"2"9;
"A"
$PN"1"15;
%"GND"
"1","(1125,4725)","0","mstr_symbols","I3";
;
VOLTAGE"0"
BOM_COST"SB"
SIZE"1B"
CDS_LIB"mstr_symbols"
BODY_TYPE"PLUMBING"
ROOM"SB_DECOUPLING"
HDL_POWER"GND";
"A\NAC"5;
%"CAP_A"
"1","(-3100,2750)","0","dev_discrete","I30";
;
LOCATION"C8B2"
PART_NUMBER"E15431-004"
VALUE"22.0UF"
TOLERANCE"20%"
PACK_TYPE"0603V"
VOLTAGE"4V"
MATERIAL"X6S"
CDS_LOCATION"C8B2"
BOM_COST"SB"
CDS_LIB"dev_discrete"
CDS_SEC"1"
$SEC"1"
ROOM"SB_DECOUPLING";
"B"
$PN"2"11;
"A"
$PN"1"10;
%"P1V8_PCH_STBY"
"1","(-1975,2175)","0","mstr_symbols","I31";
;
VOLTAGE"1.8V"
BOM_COST"SB"
CDS_LIB"mstr_symbols"
BODY_TYPE"PLUMBING"
ROOM"SB_DECOUPLING"
HDL_POWER"P1V8_PCH_STBY";
"G\NAC"6;
%"CAP_A"
"1","(-1975,1900)","0","dev_discrete","I32";
;
LOCATION"C8B3"
PART_NUMBER"E15431-004"
VALUE"22.0UF"
TOLERANCE"20%"
PACK_TYPE"0603V"
VOLTAGE"4V"
MATERIAL"X6S"
CDS_LOCATION"C8B3"
BOM_COST"SB"
CDS_LIB"dev_discrete"
CDS_SEC"1"
$SEC"1"
ROOM"SB_DECOUPLING";
"B"
$PN"2"7;
"A"
$PN"1"6;
%"GND"
"1","(-1975,1575)","0","mstr_symbols","I33";
;
VOLTAGE"0.0V"
CDS_LIB"mstr_symbols"
SIZE"1B"
BOM_COST"SB"
BODY_TYPE"PLUMBING"
ROOM"SB_DECOUPLING"
HDL_POWER"GND";
"A\NAC"7;
%"CAP_A"
"1","(-3825,3925)","0","dev_discrete","I34";
;
LOCATION"C2N25"
PART_NUMBER"D97712-004"
VALUE"1.0UF"
TOLERANCE"10%"
PACK_TYPE"0402V"
VOLTAGE"6.3V"
MATERIAL"X6S"
CDS_LOCATION"C2N25"
BOM_COST"SB"
CDS_LIB"dev_discrete"
CDS_SEC"1"
$SEC"1"
ROOM"SB_DECOUPLING";
"B"
$PN"2"9;
"A"
$PN"1"15;
%"GND"
"1","(-4325,4575)","0","mstr_symbols","I35";
;
VOLTAGE"0"
BOM_COST"SB"
CDS_LIB"mstr_symbols"
SIZE"1B"
BODY_TYPE"PLUMBING"
ROOM"SB_DECOUPLING"
HDL_POWER"GND";
"A\NAC"8;
%"CAP_A"
"1","(-4200,3925)","0","dev_discrete","I37";
;
LOCATION"C2M16"
PART_NUMBER"D97712-004"
VALUE"1.0UF"
TOLERANCE"10%"
PACK_TYPE"0402V"
VOLTAGE"6.3V"
MATERIAL"X6S"
CDS_LOCATION"C2M16"
BOM_COST"SB"
CDS_LIB"dev_discrete"
CDS_SEC"1"
$SEC"1"
ROOM"SB_DECOUPLING";
"B"
$PN"2"9;
"A"
$PN"1"15;
%"CAP_A"
"1","(-3525,2750)","0","dev_discrete","I38";
;
LOCATION"C7D3"
PART_NUMBER"E15431-004"
VALUE"22.0UF"
TOLERANCE"20%"
PACK_TYPE"0603V"
VOLTAGE"4V"
MATERIAL"X6S"
CDS_LOCATION"C7D3"
BOM_COST"SB"
CDS_LIB"dev_discrete"
CDS_SEC"1"
$SEC"1"
ROOM"SB_DECOUPLING";
"B"
$PN"2"11;
"A"
$PN"1"10;
%"CAP_A"
"1","(-3925,2750)","0","dev_discrete","I39";
;
LOCATION"C8B4"
PART_NUMBER"E15431-004"
VALUE"22.0UF"
TOLERANCE"20%"
PACK_TYPE"0603V"
VOLTAGE"4V"
MATERIAL"X6S"
CDS_LOCATION"C8B4"
BOM_COST"SB"
CDS_LIB"dev_discrete"
CDS_SEC"1"
$SEC"1"
ROOM"SB_DECOUPLING";
"B"
$PN"2"11;
"A"
$PN"1"10;
%"CAP_A"
"1","(1725,2650)","0","dev_discrete","I4";
;
LOCATION"C2N26"
PART_NUMBER"D97712-004"
VALUE"1.0UF"
TOLERANCE"10%"
PACK_TYPE"0402V"
VOLTAGE"6.3V"
MATERIAL"X6S"
CDS_LOCATION"C2N26"
BOM_COST"SB"
CDS_LIB"dev_discrete"
CDS_SEC"1"
$SEC"1"
ROOM"SB_DECOUPLING";
"B"
$PN"2"2;
"A"
$PN"1"20;
%"GND"
"1","(-4375,3575)","0","mstr_symbols","I40";
;
VOLTAGE"0"
BOM_COST"SB"
SIZE"1B"
CDS_LIB"mstr_symbols"
BODY_TYPE"PLUMBING"
ROOM"SB_DECOUPLING"
HDL_POWER"GND";
"A\NAC"9;
%"CAP_A"
"1","(-4350,2750)","0","dev_discrete","I41";
;
LOCATION"C8B1"
PART_NUMBER"E15431-004"
VALUE"22.0UF"
TOLERANCE"20%"
PACK_TYPE"0603V"
VOLTAGE"4V"
MATERIAL"X6S"
CDS_LOCATION"C8B1"
BOM_COST"SB"
CDS_LIB"dev_discrete"
CDS_SEC"1"
$SEC"1"
ROOM"SB_DECOUPLING";
"B"
$PN"2"11;
"A"
$PN"1"10;
%"CAP_A"
"1","(-4600,3925)","0","dev_discrete","I42";
;
PART_NUMBER"D97712-004"
VALUE"1.0UF"
TOLERANCE"10%"
PACK_TYPE"0402V"
VOLTAGE"6.3V"
MATERIAL"X6S"
LOCATION"C3N23"
CDS_LOCATION"C3N23"
BOM_COST"SB"
CDS_LIB"dev_discrete"
CDS_SEC"1"
$SEC"1"
ROOM"SB_DECOUPLING";
"B"
$PN"2"9;
"A"
$PN"1"15;
%"CAP_A"
"1","(-4725,2750)","0","dev_discrete","I43";
;
LOCATION"C2M1"
PART_NUMBER"E15431-004"
VALUE"22.0UF"
TOLERANCE"20%"
PACK_TYPE"0603V"
VOLTAGE"4V"
MATERIAL"X6S"
CDS_LOCATION"C2M1"
BOM_COST"SB"
CDS_LIB"dev_discrete"
CDS_SEC"1"
$SEC"1"
ROOM"SB_DECOUPLING";
"B"
$PN"2"11;
"A"
$PN"1"10;
%"P1V8_PCH_STBY"
"1","(-4850,3025)","0","mstr_symbols","I44";
;
VOLTAGE"1.8V"
BOM_COST"SB"
CDS_LIB"mstr_symbols"
BODY_TYPE"PLUMBING"
ROOM"SB_DECOUPLING"
HDL_POWER"P1V8_PCH_STBY";
"G\NAC"10;
%"CAP_A"
"1","(-5150,2750)","0","dev_discrete","I45";
;
LOCATION"C2M2"
PART_NUMBER"E15431-004"
VALUE"22.0UF"
TOLERANCE"20%"
PACK_TYPE"0603V"
VOLTAGE"4V"
MATERIAL"X6S"
CDS_LOCATION"C2M2"
BOM_COST"SB"
CDS_LIB"dev_discrete"
CDS_SEC"1"
$SEC"1"
ROOM"SB_DECOUPLING";
"B"
$PN"2"11;
"A"
$PN"1"10;
%"GND"
"1","(-4075,2425)","0","mstr_symbols","I46";
;
VOLTAGE"0"
SIZE"1B"
CDS_LIB"mstr_symbols"
BOM_COST"SB"
BODY_TYPE"PLUMBING"
ROOM"SB_DECOUPLING"
HDL_POWER"GND";
"A\NAC"11;
%"CAP_A"
"1","(-3600,1475)","0","dev_discrete","I47";
;
LOCATION"C2N15"
PART_NUMBER"D97712-004"
VALUE"1.0UF"
TOLERANCE"10%"
PACK_TYPE"0402V"
VOLTAGE"6.3V"
MATERIAL"X6S"
CDS_LOCATION"C2N15"
BOM_COST"SB"
CDS_LIB"dev_discrete"
CDS_SEC"1"
$SEC"1"
ROOM"SB_DECOUPLING";
"B"
$PN"2"12;
"A"
$PN"1"13;
%"GND"
"1","(-3750,1150)","0","mstr_symbols","I48";
;
VOLTAGE"0"
BOM_COST"SB"
CDS_LIB"mstr_symbols"
SIZE"1B"
BODY_TYPE"PLUMBING"
ROOM"SB_DECOUPLING"
HDL_POWER"GND";
"A\NAC"12;
%"CAP_A"
"1","(-3975,1475)","0","dev_discrete","I49";
;
LOCATION"C3N21"
PART_NUMBER"D97712-004"
VALUE"1.0UF"
TOLERANCE"10%"
PACK_TYPE"0402V"
VOLTAGE"6.3V"
MATERIAL"X6S"
CDS_LOCATION"C3N21"
BOM_COST"SB"
CDS_LIB"dev_discrete"
CDS_SEC"1"
$SEC"1"
ROOM"SB_DECOUPLING";
"B"
$PN"2"12;
"A"
$PN"1"13;
%"CAP_A"
"1","(-4350,1475)","0","dev_discrete","I50";
;
LOCATION"C3N25"
PART_NUMBER"D97712-004"
VALUE"1.0UF"
TOLERANCE"10%"
PACK_TYPE"0402V"
VOLTAGE"6.3V"
MATERIAL"X6S"
CDS_LOCATION"C3N25"
BOM_COST"SB"
CDS_LIB"dev_discrete"
CDS_SEC"1"
$SEC"1"
ROOM"SB_DECOUPLING";
"B"
$PN"2"12;
"A"
$PN"1"13;
%"P1V8_PCH_STBY"
"1","(-4950,1750)","0","mstr_symbols","I51";
;
VOLTAGE"1.8V"
BOM_COST"SB"
CDS_LIB"mstr_symbols"
BODY_TYPE"PLUMBING"
ROOM"SB_DECOUPLING"
HDL_POWER"P1V8_PCH_STBY";
"G\NAC"13;
%"CAP_A"
"1","(-4775,1475)","0","dev_discrete","I52";
;
LOCATION"C2N16"
PART_NUMBER"D97712-004"
VALUE"1.0UF"
TOLERANCE"10%"
PACK_TYPE"0402V"
VOLTAGE"6.3V"
MATERIAL"X6S"
CDS_LOCATION"C2N16"
BOM_COST"SB"
CDS_LIB"dev_discrete"
CDS_SEC"1"
$SEC"1"
ROOM"SB_DECOUPLING";
"B"
$PN"2"12;
"A"
$PN"1"13;
%"CAP_A"
"1","(-5200,1475)","0","dev_discrete","I53";
;
LOCATION"C3N22"
PART_NUMBER"D97712-004"
VALUE"1.0UF"
TOLERANCE"10%"
PACK_TYPE"0402V"
VOLTAGE"6.3V"
MATERIAL"X6S"
CDS_LOCATION"C3N22"
BOM_COST"SB"
CDS_LIB"dev_discrete"
CDS_SEC"1"
$SEC"1"
ROOM"SB_DECOUPLING";
"B"
$PN"2"12;
"A"
$PN"1"13;
%"P3V3_STBY"
"1","(-4325,5175)","0","mstr_symbols","I54";
;
VOLTAGE"3.3V"
CDS_LIB"mstr_symbols"
SIZE"1B"
BODY_TYPE"PLUMBING"
HDL_POWER"P3V3_STBY";
"G\NAC"14;
%"P3V3_STBY"
"1","(-4375,4250)","0","mstr_symbols","I55";
;
VOLTAGE"3.3V"
SIZE"1B"
CDS_LIB"mstr_symbols"
BODY_TYPE"PLUMBING"
HDL_POWER"P3V3_STBY";
"G\NAC"15;
%"P3V3_STBY"
"1","(-1475,4225)","0","mstr_symbols","I58";
;
VOLTAGE"3.3V"
SIZE"1B"
CDS_LIB"mstr_symbols"
BODY_TYPE"PLUMBING"
HDL_POWER"P3V3_STBY";
"G\NAC"16;
%"P3V3_STBY"
"1","(1125,5200)","0","mstr_symbols","I59";
;
VOLTAGE"3.3V"
CDS_LIB"mstr_symbols"
SIZE"1B"
BODY_TYPE"PLUMBING"
HDL_POWER"P3V3_STBY";
"G\NAC"17;
%"GND"
"1","(1175,3600)","0","mstr_symbols","I6";
;
VOLTAGE"0"
BOM_COST"SB"
SIZE"1B"
CDS_LIB"mstr_symbols"
BODY_TYPE"PLUMBING"
ROOM"SB_DECOUPLING"
HDL_POWER"GND";
"A\NAC"18;
%"P3V3_STBY"
"1","(1175,4175)","0","mstr_symbols","I60";
;
VOLTAGE"3.3V"
CDS_LIB"mstr_symbols"
SIZE"1B"
BODY_TYPE"PLUMBING"
HDL_POWER"P3V3_STBY";
"G\NAC"19;
%"P3V3_STBY"
"1","(650,2925)","0","mstr_symbols","I61";
;
VOLTAGE"3.3V"
CDS_LIB"mstr_symbols"
SIZE"1B"
BODY_TYPE"PLUMBING"
HDL_POWER"P3V3_STBY";
"G\NAC"20;
%"P3V3_STBY"
"1","(1925,1875)","0","mstr_symbols","I62";
;
VOLTAGE"3.3V"
CDS_LIB"mstr_symbols"
SIZE"1B"
BODY_TYPE"PLUMBING"
HDL_POWER"P3V3_STBY";
"G\NAC"21;
%"CAP_A"
"1","(1175,3900)","0","dev_discrete","I7";
;
LOCATION"C2N19"
PART_NUMBER"D97712-004"
VALUE"1.0UF"
TOLERANCE"10%"
PACK_TYPE"0402V"
VOLTAGE"6.3V"
MATERIAL"X6S"
CDS_LOCATION"C2N19"
BOM_COST"SB"
CDS_LIB"dev_discrete"
CDS_SEC"1"
$SEC"1"
ROOM"SB_DECOUPLING";
"B"
$PN"2"18;
"A"
$PN"1"19;
%"CAP"
"1","(1300,2650)","0","mstr_discrete","I8";
;
LOCATION"C2N24"
PART_NUMBER"E15431-002"
VALUE"10UF"
TOLERANCE"20%"
PACK_TYPE"0603"
VOLTAGE"6.3V"
MATERIAL"X6S"
CDS_LIB"mstr_discrete"
BOM_COST"SB"
CDS_SEC"1"
$SEC"1"
CDS_LOCATION"C2N24"
ROOM"SB_DECOUPLING";
"A"
$PN"1"20;
"B"
$PN"2"2;
%"CAP"
"1","(875,2650)","0","mstr_discrete","I9";
;
LOCATION"C2N22"
PART_NUMBER"E15431-002"
VALUE"10UF"
TOLERANCE"20%"
PACK_TYPE"0603"
VOLTAGE"6.3V"
MATERIAL"X6S"
CDS_LIB"mstr_discrete"
BOM_COST"SB"
CDS_SEC"1"
$SEC"1"
CDS_LOCATION"C2N22"
ROOM"SB_DECOUPLING";
"A"
$PN"1"20;
"B"
$PN"2"2;
END.
